# T6G (Grand Teton) — schematic netlist excerpt (pin names and nets, part order shuffled) for the footprints in the layout excerpt that follows; sources: Cadence DE-HDL packaged netlist, KiCad conversion of 04192023_DAF0TMB3IC0_F0TG_MB_C_brd_V02_OCP.brd

R6792  Q_RES  0 5% CHIP  pkg 0402LF  page 81 : A = RST_RT_CPU1_P2_PERST_R_N ; B = RST_RT_CPU1_P2_PERST_R2_N
R1185  Q_RES  1K 1% CHIP  pkg 0402LF  page 83 : A = PVDDCR_CPU0_P0_PMALERT ; B = P3V3_AUX

(kicad_pcb
	(version 20260206)
	(generator "pcbnew")
	(generator_version "10.0")
	(general
		(thickness 1.6)
		(legacy_teardrops no)
	)
	(paper "A4")
	(title_block
		(title "04192023_DAF0TMB3IC0_F0TG_MB_C_brd_V02_OCP.brd")
		(comment 1 "Grand Teton / footprints 1988-1989 of 8354")
	)
	(layers
		(0 "F.Cu" signal "TOP")
		(4 "In1.Cu" signal "GND")
		(6 "In2.Cu" signal "IN1")
		(8 "In3.Cu" signal "GND1")
		(10 "In4.Cu" signal "IN2")
		(12 "In5.Cu" signal "GND2")
		(14 "In6.Cu" signal "IN3")
		(16 "In7.Cu" signal "GND3")
		(18 "In8.Cu" signal "VCC")
		(20 "In9.Cu" signal "VCC1")
		(22 "In10.Cu" signal "GND4")
		(24 "In11.Cu" signal "IN4")
		(26 "In12.Cu" signal "GND5")
		(28 "In13.Cu" signal "IN5")
		(30 "In14.Cu" signal "GND6")
		(32 "In15.Cu" signal "IN6")
		(34 "In16.Cu" signal "GND7")
		(2 "B.Cu" signal "BOTTOM")
		(9 "F.Adhes" user "F.Adhesive")
		(11 "B.Adhes" user "B.Adhesive")
		(13 "F.Paste" user "Package Geometry/Pastemask Top")
		(15 "B.Paste" user "Package Geometry/Pastemask Bottom")
		(5 "F.SilkS" user "Ref Des/Silkscreen Top")
		(7 "B.SilkS" user "Ref Des/Silkscreen Bottom")
		(1 "F.Mask" user "Board Geometry/Soldermask Top")
		(3 "B.Mask" user "Board Geometry/Soldermask Bottom")
		(17 "Dwgs.User" user "User.Drawings")
		(19 "Cmts.User" user "User.Comments")
		(21 "Eco1.User" user "User.Eco1")
		(23 "Eco2.User" user "User.Eco2")
		(25 "Edge.Cuts" user "Board Geometry/Outline")
		(27 "Margin" user)
		(31 "F.CrtYd" user "Package Geometry/Place Bound Top")
		(29 "B.CrtYd" user "Package Geometry/Place Bound Bottom")
		(35 "F.Fab" user "Ref Des/Assembly Top")
		(33 "B.Fab" user "Ref Des/Assembly Bottom")
	)
	(footprint ""
		(layer "F.Cu")
		(at 197.523608 -105.497376 180)
		(property "Reference" "R1185"
			(at 0 0 180)
			(layer "F.SilkS")
			(hide yes)
			(effects
				(font
					(size 1.27 1.27)
				)
			)
		)
		(property "Value" ""
			(at 0 0 180)
			(layer "F.Fab")
			(effects
				(font
					(size 1.27 1.27)
				)
			)
		)
		(duplicate_pad_numbers_are_jumpers no)
		(fp_line
			(start 0.7874 0.4064)
			(end -0.7874 0.4064)
			(stroke
				(width 0.1524)
				(type default)
			)
			(layer "F.SilkS")
		)
		(fp_line
			(start 0.7874 -0.4064)
			(end 0.7874 0.4064)
			(stroke
				(width 0.1524)
				(type default)
			)
			(layer "F.SilkS")
		)
		(fp_line
			(start -0.7874 0.4064)
			(end -0.7874 -0.4064)
			(stroke
				(width 0.1524)
				(type default)
			)
			(layer "F.SilkS")
		)
		(fp_line
			(start -0.7874 -0.4064)
			(end 0.7874 -0.4064)
			(stroke
				(width 0.1524)
				(type default)
			)
			(layer "F.SilkS")
		)
		(fp_line
			(start 0.67945 0.3048)
			(end 0.120396 0.3048)
			(stroke
				(width 0.1)
				(type default)
			)
			(layer "F.Fab")
		)
		(fp_line
			(start 0.67945 -0.3048)
			(end 0.67945 0.3048)
			(stroke
				(width 0.1)
				(type default)
			)
			(layer "F.Fab")
		)
		(fp_line
			(start 0.12065 -0.2794)
			(end 0.12065 -0.3048)
			(stroke
				(width 0.1)
				(type default)
			)
			(layer "F.Fab")
		)
		(fp_line
			(start 0.12065 -0.3048)
			(end 0.67945 -0.3048)
			(stroke
				(width 0.1)
				(type default)
			)
			(layer "F.Fab")
		)
		(fp_line
			(start 0.120396 0.3048)
			(end 0.120396 0.2794)
			(stroke
				(width 0.1)
				(type default)
			)
			(layer "F.Fab")
		)
		(fp_line
			(start 0.120396 0.2794)
			(end -0.12065 0.2794)
			(stroke
				(width 0.1)
				(type default)
			)
			(layer "F.Fab")
		)
		(fp_line
			(start -0.12065 0.3048)
			(end -0.67945 0.3048)
			(stroke
				(width 0.1)
				(type default)
			)
			(layer "F.Fab")
		)
		(fp_line
			(start -0.12065 0.2794)
			(end -0.12065 0.3048)
			(stroke
				(width 0.1)
				(type default)
			)
			(layer "F.Fab")
		)
		(fp_line
			(start -0.12065 -0.2794)
			(end 0.12065 -0.2794)
			(stroke
				(width 0.1)
				(type default)
			)
			(layer "F.Fab")
		)
		(fp_line
			(start -0.12065 -0.305054)
			(end -0.12065 -0.2794)
			(stroke
				(width 0.1)
				(type default)
			)
			(layer "F.Fab")
		)
		(fp_line
			(start -0.67945 0.3048)
			(end -0.67945 -0.305054)
			(stroke
				(width 0.1)
				(type default)
			)
			(layer "F.Fab")
		)
		(fp_line
			(start -0.67945 -0.305054)
			(end -0.12065 -0.305054)
			(stroke
				(width 0.1)
				(type default)
			)
			(layer "F.Fab")
		)
		(pad "1" smd circle
			(at -0.40005 0 180)
			(size 0 0)
			(layers "F.Cu" "F.Mask" "F.Paste")
			(net "PVDDCR_CPU0_P0_PMALERT")
		)
		(pad "2" smd circle
			(at 0.40005 0 180)
			(size 0 0)
			(layers "F.Cu" "F.Mask" "F.Paste")
			(net "P3V3_AUX")
		)
	)
	(footprint ""
		(layer "F.Cu")
		(at 187.280296 -133.477762 -90)
		(property "Reference" "R6792"
			(at 0 0 270)
			(layer "F.SilkS")
			(hide yes)
			(effects
				(font
					(size 1.27 1.27)
				)
			)
		)
		(property "Value" ""
			(at 0 0 270)
			(layer "F.Fab")
			(effects
				(font
					(size 1.27 1.27)
				)
			)
		)
		(duplicate_pad_numbers_are_jumpers no)
		(fp_line
			(start -0.7874 0.4064)
			(end -0.7874 -0.4064)
			(stroke
				(width 0.1524)
				(type default)
			)
			(layer "F.SilkS")
		)
		(fp_line
			(start 0.7874 0.4064)
			(end -0.7874 0.4064)
			(stroke
				(width 0.1524)
				(type default)
			)
			(layer "F.SilkS")
		)
		(fp_line
			(start -0.7874 -0.4064)
			(end 0.7874 -0.4064)
			(stroke
				(width 0.1524)
				(type default)
			)
			(layer "F.SilkS")
		)
		(fp_line
			(start 0.7874 -0.4064)
			(end 0.7874 0.4064)
			(stroke
				(width 0.1524)
				(type default)
			)
			(layer "F.SilkS")
		)
		(fp_line
			(start -0.67945 0.3048)
			(end -0.67945 -0.305054)
			(stroke
				(width 0.1)
				(type default)
			)
			(layer "F.Fab")
		)
		(fp_line
			(start -0.12065 0.3048)
			(end -0.67945 0.3048)
			(stroke
				(width 0.1)
				(type default)
			)
			(layer "F.Fab")
		)
		(fp_line
			(start 0.120396 0.3048)
			(end 0.120396 0.2794)
			(stroke
				(width 0.1)
				(type default)
			)
			(layer "F.Fab")
		)
		(fp_line
			(start 0.67945 0.3048)
			(end 0.120396 0.3048)
			(stroke
				(width 0.1)
				(type default)
			)
			(layer "F.Fab")
		)
		(fp_line
			(start -0.12065 0.2794)
			(end -0.12065 0.3048)
			(stroke
				(width 0.1)
				(type default)
			)
			(layer "F.Fab")
		)
		(fp_line
			(start 0.120396 0.2794)
			(end -0.12065 0.2794)
			(stroke
				(width 0.1)
				(type default)
			)
			(layer "F.Fab")
		)
		(fp_line
			(start -0.12065 -0.2794)
			(end 0.12065 -0.2794)
			(stroke
				(width 0.1)
				(type default)
			)
			(layer "F.Fab")
		)
		(fp_line
			(start 0.12065 -0.2794)
			(end 0.12065 -0.3048)
			(stroke
				(width 0.1)
				(type default)
			)
			(layer "F.Fab")
		)
		(fp_line
			(start 0.12065 -0.3048)
			(end 0.67945 -0.3048)
			(stroke
				(width 0.1)
				(type default)
			)
			(layer "F.Fab")
		)
		(fp_line
			(start 0.67945 -0.3048)
			(end 0.67945 0.3048)
			(stroke
				(width 0.1)
				(type default)
			)
			(layer "F.Fab")
		)
		(fp_line
			(start -0.67945 -0.305054)
			(end -0.12065 -0.305054)
			(stroke
				(width 0.1)
				(type default)
			)
			(layer "F.Fab")
		)
		(fp_line
			(start -0.12065 -0.305054)
			(end -0.12065 -0.2794)
			(stroke
				(width 0.1)
				(type default)
			)
			(layer "F.Fab")
		)
		(pad "1" smd circle
			(at -0.40005 0 270)
			(size 0 0)
			(layers "F.Cu" "F.Mask" "F.Paste")
			(net "RST_RT_CPU1_P2_PERST_R_N")
		)
		(pad "2" smd circle
			(at 0.40005 0 270)
			(size 0 0)
			(layers "F.Cu" "F.Mask" "F.Paste")
			(net "RST_RT_CPU1_P2_PERST_R2_N")
		)
	)
)
